(kicad_pcb
	(version 20260206)
	(generator "pcbnew")
	(generator_version "10.0")
	(general
		(thickness 1.6)
		(legacy_teardrops no)
	)
	(paper "A4")
	(title_block
		(title "03242023_DA0F0TMBIJ0_F0T_Motherboard_J_brd_V01_OCP.brd")
		(comment 1 "Grand Teton / footprints 4735-4740 of 6105")
	)
	(layers
		(0 "F.Cu" signal "TOP")
		(4 "In1.Cu" signal "GND")
		(6 "In2.Cu" signal "IN1")
		(8 "In3.Cu" signal "GND1")
		(10 "In4.Cu" signal "IN2")
		(12 "In5.Cu" signal "GND2")
		(14 "In6.Cu" signal "IN3")
		(16 "In7.Cu" signal "GND3")
		(18 "In8.Cu" signal "VCC")
		(20 "In9.Cu" signal "VCC1")
		(22 "In10.Cu" signal "GND4")
		(24 "In11.Cu" signal "IN4")
		(26 "In12.Cu" signal "GND5")
		(28 "In13.Cu" signal "IN5")
		(30 "In14.Cu" signal "GND6")
		(32 "In15.Cu" signal "IN6")
		(34 "In16.Cu" signal "GND7")
		(2 "B.Cu" signal "BOTTOM")
		(9 "F.Adhes" user "F.Adhesive")
		(11 "B.Adhes" user "B.Adhesive")
		(13 "F.Paste" user "Package Geometry/Pastemask Top")
		(15 "B.Paste" user "Package Geometry/Pastemask Bottom")
		(5 "F.SilkS" user "Ref Des/Silkscreen Top")
		(7 "B.SilkS" user "Ref Des/Silkscreen Bottom")
		(1 "F.Mask" user "Board Geometry/Soldermask Top")
		(3 "B.Mask" user "Board Geometry/Soldermask Bottom")
		(17 "Dwgs.User" user "User.Drawings")
		(19 "Cmts.User" user "User.Comments")
		(21 "Eco1.User" user "User.Eco1")
		(23 "Eco2.User" user "User.Eco2")
		(25 "Edge.Cuts" user "Board Geometry/Outline")
		(27 "Margin" user)
		(31 "F.CrtYd" user "Package Geometry/Place Bound Top")
		(29 "B.CrtYd" user "Package Geometry/Place Bound Bottom")
		(35 "F.Fab" user "Ref Des/Assembly Top")
		(33 "B.Fab" user "Ref Des/Assembly Bottom")
	)
	(footprint ""
		(layer "B.Cu")
		(at 53.746908 -193.25971 -90)
		(property "Reference" "R92"
			(at 0 0 90)
			(layer "B.SilkS")
			(hide yes)
			(effects
				(font
					(size 1.27 1.27)
				)
				(justify mirror)
			)
		)
		(property "Value" ""
			(at 0 0 90)
			(layer "B.Fab")
			(effects
				(font
					(size 1.27 1.27)
				)
				(justify mirror)
			)
		)
		(duplicate_pad_numbers_are_jumpers no)
		(fp_line
			(start -0.7874 0.4064)
			(end 0.7874 0.4064)
			(stroke
				(width 0.1524)
				(type default)
			)
			(layer "B.SilkS")
		)
		(fp_line
			(start 0.7874 0.4064)
			(end 0.7874 -0.4064)
			(stroke
				(width 0.1524)
				(type default)
			)
			(layer "B.SilkS")
		)
		(fp_line
			(start -0.7874 -0.4064)
			(end -0.7874 0.4064)
			(stroke
				(width 0.1524)
				(type default)
			)
			(layer "B.SilkS")
		)
		(fp_line
			(start 0.7874 -0.4064)
			(end -0.7874 -0.4064)
			(stroke
				(width 0.1524)
				(type default)
			)
			(layer "B.SilkS")
		)
		(fp_line
			(start -0.67945 0.3048)
			(end -0.120396 0.3048)
			(stroke
				(width 0.1)
				(type default)
			)
			(layer "B.Fab")
		)
		(fp_line
			(start -0.120396 0.3048)
			(end -0.120396 0.2794)
			(stroke
				(width 0.1)
				(type default)
			)
			(layer "B.Fab")
		)
		(fp_line
			(start 0.12065 0.3048)
			(end 0.67945 0.3048)
			(stroke
				(width 0.1)
				(type default)
			)
			(layer "B.Fab")
		)
		(fp_line
			(start 0.67945 0.3048)
			(end 0.67945 -0.305054)
			(stroke
				(width 0.1)
				(type default)
			)
			(layer "B.Fab")
		)
		(fp_line
			(start -0.120396 0.2794)
			(end 0.12065 0.2794)
			(stroke
				(width 0.1)
				(type default)
			)
			(layer "B.Fab")
		)
		(fp_line
			(start 0.12065 0.2794)
			(end 0.12065 0.3048)
			(stroke
				(width 0.1)
				(type default)
			)
			(layer "B.Fab")
		)
		(fp_line
			(start -0.12065 -0.2794)
			(end -0.12065 -0.3048)
			(stroke
				(width 0.1)
				(type default)
			)
			(layer "B.Fab")
		)
		(fp_line
			(start 0.12065 -0.2794)
			(end -0.12065 -0.2794)
			(stroke
				(width 0.1)
				(type default)
			)
			(layer "B.Fab")
		)
		(fp_line
			(start -0.67945 -0.3048)
			(end -0.67945 0.3048)
			(stroke
				(width 0.1)
				(type default)
			)
			(layer "B.Fab")
		)
		(fp_line
			(start -0.12065 -0.3048)
			(end -0.67945 -0.3048)
			(stroke
				(width 0.1)
				(type default)
			)
			(layer "B.Fab")
		)
		(fp_line
			(start 0.12065 -0.305054)
			(end 0.12065 -0.2794)
			(stroke
				(width 0.1)
				(type default)
			)
			(layer "B.Fab")
		)
		(fp_line
			(start 0.67945 -0.305054)
			(end 0.12065 -0.305054)
			(stroke
				(width 0.1)
				(type default)
			)
			(layer "B.Fab")
		)
		(pad "1" smd circle
			(at 0.40005 0 90)
			(size 0 0)
			(layers "B.Cu" "B.Mask" "B.Paste")
			(net "PVNN_TERM_CPU1")
		)
		(pad "2" smd circle
			(at -0.40005 0 90)
			(size 0 0)
			(layers "B.Cu" "B.Mask" "B.Paste")
			(net "PU_CPU1_UPI2_AC_COUPLING")
		)
	)
	(footprint ""
		(layer "B.Cu")
		(at 326.743822 -70.207378)
		(property "Reference" "C1250"
			(at 0 0 0)
			(layer "B.SilkS")
			(hide yes)
			(effects
				(font
					(size 1.27 1.27)
				)
				(justify mirror)
			)
		)
		(property "Value" ""
			(at 0 0 0)
			(layer "B.Fab")
			(effects
				(font
					(size 1.27 1.27)
				)
				(justify mirror)
			)
		)
		(duplicate_pad_numbers_are_jumpers no)
		(fp_line
			(start -0.7874 -0.4064)
			(end -0.7874 0.4064)
			(stroke
				(width 0.1524)
				(type default)
			)
			(layer "B.SilkS")
		)
		(fp_line
			(start -0.7874 0.4064)
			(end 0.7874 0.4064)
			(stroke
				(width 0.1524)
				(type default)
			)
			(layer "B.SilkS")
		)
		(fp_line
			(start 0.7874 -0.4064)
			(end -0.7874 -0.4064)
			(stroke
				(width 0.1524)
				(type default)
			)
			(layer "B.SilkS")
		)
		(fp_line
			(start 0.7874 0.4064)
			(end 0.7874 -0.4064)
			(stroke
				(width 0.1524)
				(type default)
			)
			(layer "B.SilkS")
		)
		(fp_line
			(start -0.67945 -0.3048)
			(end -0.67945 0.3048)
			(stroke
				(width 0.1)
				(type default)
			)
			(layer "B.Fab")
		)
		(fp_line
			(start -0.67945 0.3048)
			(end -0.120396 0.3048)
			(stroke
				(width 0.1)
				(type default)
			)
			(layer "B.Fab")
		)
		(fp_line
			(start -0.12065 -0.3048)
			(end -0.67945 -0.3048)
			(stroke
				(width 0.1)
				(type default)
			)
			(layer "B.Fab")
		)
		(fp_line
			(start -0.12065 -0.2794)
			(end -0.12065 -0.3048)
			(stroke
				(width 0.1)
				(type default)
			)
			(layer "B.Fab")
		)
		(fp_line
			(start -0.120396 0.2794)
			(end 0.12065 0.2794)
			(stroke
				(width 0.1)
				(type default)
			)
			(layer "B.Fab")
		)
		(fp_line
			(start -0.120396 0.3048)
			(end -0.120396 0.2794)
			(stroke
				(width 0.1)
				(type default)
			)
			(layer "B.Fab")
		)
		(fp_line
			(start 0.12065 -0.305054)
			(end 0.12065 -0.2794)
			(stroke
				(width 0.1)
				(type default)
			)
			(layer "B.Fab")
		)
		(fp_line
			(start 0.12065 -0.2794)
			(end -0.12065 -0.2794)
			(stroke
				(width 0.1)
				(type default)
			)
			(layer "B.Fab")
		)
		(fp_line
			(start 0.12065 0.2794)
			(end 0.12065 0.3048)
			(stroke
				(width 0.1)
				(type default)
			)
			(layer "B.Fab")
		)
		(fp_line
			(start 0.12065 0.3048)
			(end 0.67945 0.3048)
			(stroke
				(width 0.1)
				(type default)
			)
			(layer "B.Fab")
		)
		(fp_line
			(start 0.67945 -0.305054)
			(end 0.12065 -0.305054)
			(stroke
				(width 0.1)
				(type default)
			)
			(layer "B.Fab")
		)
		(fp_line
			(start 0.67945 0.3048)
			(end 0.67945 -0.305054)
			(stroke
				(width 0.1)
				(type default)
			)
			(layer "B.Fab")
		)
		(pad "1" smd circle
			(at 0.40005 0 180)
			(size 0 0)
			(layers "B.Cu" "B.Mask" "B.Paste")
			(net "P1V05_PCH_AUX")
		)
		(pad "2" smd circle
			(at -0.40005 0 180)
			(size 0 0)
			(layers "B.Cu" "B.Mask" "B.Paste")
			(net "GND")
		)
	)
	(footprint ""
		(layer "B.Cu")
		(at 164.64788 -117.566948 180)
		(property "Reference" "R919"
			(at 0 0 0)
			(layer "B.SilkS")
			(hide yes)
			(effects
				(font
					(size 1.27 1.27)
				)
				(justify mirror)
			)
		)
		(property "Value" ""
			(at 0 0 0)
			(layer "B.Fab")
			(effects
				(font
					(size 1.27 1.27)
				)
				(justify mirror)
			)
		)
		(duplicate_pad_numbers_are_jumpers no)
		(fp_line
			(start 0.7874 0.4064)
			(end 0.7874 -0.4064)
			(stroke
				(width 0.1524)
				(type default)
			)
			(layer "B.SilkS")
		)
		(fp_line
			(start 0.7874 -0.4064)
			(end -0.7874 -0.4064)
			(stroke
				(width 0.1524)
				(type default)
			)
			(layer "B.SilkS")
		)
		(fp_line
			(start -0.7874 0.4064)
			(end 0.7874 0.4064)
			(stroke
				(width 0.1524)
				(type default)
			)
			(layer "B.SilkS")
		)
		(fp_line
			(start -0.7874 -0.4064)
			(end -0.7874 0.4064)
			(stroke
				(width 0.1524)
				(type default)
			)
			(layer "B.SilkS")
		)
		(fp_line
			(start 0.67945 0.3048)
			(end 0.67945 -0.305054)
			(stroke
				(width 0.1)
				(type default)
			)
			(layer "B.Fab")
		)
		(fp_line
			(start 0.67945 -0.305054)
			(end 0.12065 -0.305054)
			(stroke
				(width 0.1)
				(type default)
			)
			(layer "B.Fab")
		)
		(fp_line
			(start 0.12065 0.3048)
			(end 0.67945 0.3048)
			(stroke
				(width 0.1)
				(type default)
			)
			(layer "B.Fab")
		)
		(fp_line
			(start 0.12065 0.2794)
			(end 0.12065 0.3048)
			(stroke
				(width 0.1)
				(type default)
			)
			(layer "B.Fab")
		)
		(fp_line
			(start 0.12065 -0.2794)
			(end -0.12065 -0.2794)
			(stroke
				(width 0.1)
				(type default)
			)
			(layer "B.Fab")
		)
		(fp_line
			(start 0.12065 -0.305054)
			(end 0.12065 -0.2794)
			(stroke
				(width 0.1)
				(type default)
			)
			(layer "B.Fab")
		)
		(fp_line
			(start -0.120396 0.3048)
			(end -0.120396 0.2794)
			(stroke
				(width 0.1)
				(type default)
			)
			(layer "B.Fab")
		)
		(fp_line
			(start -0.120396 0.2794)
			(end 0.12065 0.2794)
			(stroke
				(width 0.1)
				(type default)
			)
			(layer "B.Fab")
		)
		(fp_line
			(start -0.12065 -0.2794)
			(end -0.12065 -0.3048)
			(stroke
				(width 0.1)
				(type default)
			)
			(layer "B.Fab")
		)
		(fp_line
			(start -0.12065 -0.3048)
			(end -0.67945 -0.3048)
			(stroke
				(width 0.1)
				(type default)
			)
			(layer "B.Fab")
		)
		(fp_line
			(start -0.67945 0.3048)
			(end -0.120396 0.3048)
			(stroke
				(width 0.1)
				(type default)
			)
			(layer "B.Fab")
		)
		(fp_line
			(start -0.67945 -0.3048)
			(end -0.67945 0.3048)
			(stroke
				(width 0.1)
				(type default)
			)
			(layer "B.Fab")
		)
		(pad "1" smd circle
			(at 0.40005 0)
			(size 0 0)
			(layers "B.Cu" "B.Mask" "B.Paste")
			(net "P3V3_AUX")
		)
		(pad "2" smd circle
			(at -0.40005 0)
			(size 0 0)
			(layers "B.Cu" "B.Mask" "B.Paste")
			(net "JTAG_PLD_JTAGEN")
		)
	)
	(footprint ""
		(layer "B.Cu")
		(at 361.617768 -326.87006 -90)
		(property "Reference" "PC1920"
			(at 0 0 90)
			(layer "B.SilkS")
			(hide yes)
			(effects
				(font
					(size 1.27 1.27)
				)
				(justify mirror)
			)
		)
		(property "Value" ""
			(at 0 0 90)
			(layer "B.Fab")
			(effects
				(font
					(size 1.27 1.27)
				)
				(justify mirror)
			)
		)
		(duplicate_pad_numbers_are_jumpers no)
		(fp_line
			(start -4.533392 2.249932)
			(end 4.533392 2.249932)
			(stroke
				(width 0.1524)
				(type default)
			)
			(layer "B.SilkS")
		)
		(fp_line
			(start 4.533392 2.249932)
			(end 4.533392 -2.249932)
			(stroke
				(width 0.1524)
				(type default)
			)
			(layer "B.SilkS")
		)
		(fp_line
			(start -4.533392 -2.249932)
			(end -4.533392 2.249932)
			(stroke
				(width 0.1524)
				(type default)
			)
			(layer "B.SilkS")
		)
		(fp_line
			(start 4.533392 -2.249932)
			(end -4.533392 -2.249932)
			(stroke
				(width 0.1524)
				(type default)
			)
			(layer "B.SilkS")
		)
		(fp_rect
			(start 5.39242 2.326132)
			(end 4.533392 -2.326132)
			(stroke
				(width 0)
				(type default)
			)
			(fill yes)
			(layer "B.SilkS")
		)
		(fp_line
			(start -3.750056 2.249932)
			(end 3.750056 2.249932)
			(stroke
				(width 0.1)
				(type default)
			)
			(layer "B.Fab")
		)
		(fp_line
			(start 3.750056 2.249932)
			(end 3.750056 -2.249932)
			(stroke
				(width 0.1)
				(type default)
			)
			(layer "B.Fab")
		)
		(fp_line
			(start -3.750056 -2.249932)
			(end -3.750056 2.249932)
			(stroke
				(width 0.1)
				(type default)
			)
			(layer "B.Fab")
		)
		(fp_line
			(start 3.750056 -2.249932)
			(end -3.750056 -2.249932)
			(stroke
				(width 0.1)
				(type default)
			)
			(layer "B.Fab")
		)
		(fp_text user "-"
			(at -4.615688 1.650238 270)
			(unlocked yes)
			(layer "B.SilkS")
			(effects
				(font
					(size 1.905 1.4224)
					(thickness 0.1524)
				)
				(justify left mirror)
			)
		)
		(fp_text user "+"
			(at 6.322314 0.786384 180)
			(unlocked yes)
			(layer "B.SilkS")
			(effects
				(font
					(size 1.905 1.4224)
					(thickness 0.1524)
				)
				(justify left mirror)
			)
		)
		(fp_text user "+"
			(at 6.322314 0.786384 180)
			(unlocked yes)
			(layer "B.Fab")
			(effects
				(font
					(size 1.905 1.4224)
					(thickness 0.1524)
				)
				(justify left mirror)
			)
		)
		(fp_text user "-"
			(at -4.8514 -0.14605 270)
			(unlocked yes)
			(layer "B.Fab")
			(effects
				(font
					(size 1.905 1.4224)
					(thickness 0.1524)
				)
				(justify left mirror)
			)
		)
		(pad "1" smd rect
			(at 3.199892 0 90)
			(size 2.413 2.8194)
			(layers "B.Cu" "B.Mask" "B.Paste")
			(net "PVCCIN_CPU0")
		)
		(pad "2" smd rect
			(at -3.199892 0 90)
			(size 2.413 2.8194)
			(layers "B.Cu" "B.Mask" "B.Paste")
			(net "GND")
		)
	)
	(footprint ""
		(layer "B.Cu")
		(at 191.47409 -79.05623 -90)
		(property "Reference" "R1290"
			(at 0 0 90)
			(layer "B.SilkS")
			(hide yes)
			(effects
				(font
					(size 1.27 1.27)
				)
				(justify mirror)
			)
		)
		(property "Value" ""
			(at 0 0 90)
			(layer "B.Fab")
			(effects
				(font
					(size 1.27 1.27)
				)
				(justify mirror)
			)
		)
		(duplicate_pad_numbers_are_jumpers no)
		(fp_line
			(start -0.7874 0.4064)
			(end 0.7874 0.4064)
			(stroke
				(width 0.1524)
				(type default)
			)
			(layer "B.SilkS")
		)
		(fp_line
			(start 0.7874 0.4064)
			(end 0.7874 -0.4064)
			(stroke
				(width 0.1524)
				(type default)
			)
			(layer "B.SilkS")
		)
		(fp_line
			(start -0.7874 -0.4064)
			(end -0.7874 0.4064)
			(stroke
				(width 0.1524)
				(type default)
			)
			(layer "B.SilkS")
		)
		(fp_line
			(start 0.7874 -0.4064)
			(end -0.7874 -0.4064)
			(stroke
				(width 0.1524)
				(type default)
			)
			(layer "B.SilkS")
		)
		(fp_line
			(start -0.67945 0.3048)
			(end -0.120396 0.3048)
			(stroke
				(width 0.1)
				(type default)
			)
			(layer "B.Fab")
		)
		(fp_line
			(start -0.120396 0.3048)
			(end -0.120396 0.2794)
			(stroke
				(width 0.1)
				(type default)
			)
			(layer "B.Fab")
		)
		(fp_line
			(start 0.12065 0.3048)
			(end 0.67945 0.3048)
			(stroke
				(width 0.1)
				(type default)
			)
			(layer "B.Fab")
		)
		(fp_line
			(start 0.67945 0.3048)
			(end 0.67945 -0.305054)
			(stroke
				(width 0.1)
				(type default)
			)
			(layer "B.Fab")
		)
		(fp_line
			(start -0.120396 0.2794)
			(end 0.12065 0.2794)
			(stroke
				(width 0.1)
				(type default)
			)
			(layer "B.Fab")
		)
		(fp_line
			(start 0.12065 0.2794)
			(end 0.12065 0.3048)
			(stroke
				(width 0.1)
				(type default)
			)
			(layer "B.Fab")
		)
		(fp_line
			(start -0.12065 -0.2794)
			(end -0.12065 -0.3048)
			(stroke
				(width 0.1)
				(type default)
			)
			(layer "B.Fab")
		)
		(fp_line
			(start 0.12065 -0.2794)
			(end -0.12065 -0.2794)
			(stroke
				(width 0.1)
				(type default)
			)
			(layer "B.Fab")
		)
		(fp_line
			(start -0.67945 -0.3048)
			(end -0.67945 0.3048)
			(stroke
				(width 0.1)
				(type default)
			)
			(layer "B.Fab")
		)
		(fp_line
			(start -0.12065 -0.3048)
			(end -0.67945 -0.3048)
			(stroke
				(width 0.1)
				(type default)
			)
			(layer "B.Fab")
		)
		(fp_line
			(start 0.12065 -0.305054)
			(end 0.12065 -0.2794)
			(stroke
				(width 0.1)
				(type default)
			)
			(layer "B.Fab")
		)
		(fp_line
			(start 0.67945 -0.305054)
			(end 0.12065 -0.305054)
			(stroke
				(width 0.1)
				(type default)
			)
			(layer "B.Fab")
		)
		(pad "1" smd rect
			(at 0.40005 0 270)
			(size 0.4572 0.508)
			(layers "B.Cu" "B.Mask" "B.Paste")
			(net "OCP_SFF_RBT_ARB_IN_R")
		)
		(pad "2" smd rect
			(at -0.40005 0 270)
			(size 0.4572 0.508)
			(layers "B.Cu" "B.Mask" "B.Paste")
			(net "OCP_SFF_RBT_ARB_IN")
		)
	)
	(footprint ""
		(layer "B.Cu")
		(at 364.342934 -252.176026 -90)
		(property "Reference" "C364"
			(at 0 0 90)
			(layer "B.SilkS")
			(hide yes)
			(effects
				(font
					(size 1.27 1.27)
				)
				(justify mirror)
			)
		)
		(property "Value" ""
			(at 0 0 90)
			(layer "B.Fab")
			(effects
				(font
					(size 1.27 1.27)
				)
				(justify mirror)
			)
		)
		(duplicate_pad_numbers_are_jumpers no)
		(fp_line
			(start -1.524 0.762)
			(end 1.524 0.762)
			(stroke
				(width 0.1524)
				(type default)
			)
			(layer "B.SilkS")
		)
		(fp_line
			(start 1.524 0.762)
			(end 1.524 -0.762)
			(stroke
				(width 0.1524)
				(type default)
			)
			(layer "B.SilkS")
		)
		(fp_line
			(start -1.524 -0.762)
			(end -1.524 0.762)
			(stroke
				(width 0.1524)
				(type default)
			)
			(layer "B.SilkS")
		)
		(fp_line
			(start 1.524 -0.762)
			(end -1.524 -0.762)
			(stroke
				(width 0.1524)
				(type default)
			)
			(layer "B.SilkS")
		)
		(fp_line
			(start -1.1049 0.724916)
			(end -1.1049 -0.724916)
			(stroke
				(width 0.1)
				(type default)
			)
			(layer "B.Fab")
		)
		(fp_line
			(start 1.1049 0.724916)
			(end -1.1049 0.724916)
			(stroke
				(width 0.1)
				(type default)
			)
			(layer "B.Fab")
		)
		(fp_line
			(start -1.1049 -0.724916)
			(end 1.1049 -0.724916)
			(stroke
				(width 0.1)
				(type default)
			)
			(layer "B.Fab")
		)
		(fp_line
			(start 1.1049 -0.724916)
			(end 1.1049 0.724916)
			(stroke
				(width 0.1)
				(type default)
			)
			(layer "B.Fab")
		)
		(pad "1" smd rect
			(at 0.889 0 270)
			(size 1.016 1.27)
			(layers "B.Cu" "B.Mask" "B.Paste")
			(net "PVCCIN_CPU0")
		)
		(pad "2" smd rect
			(at -0.889 0 270)
			(size 1.016 1.27)
			(layers "B.Cu" "B.Mask" "B.Paste")
			(net "GND")
		)
	)
)
